FILE_TYPE = CONNECTIVITY;
{Allegro Design Entry HDL 16.6-p007 (v16-6-112F) 10/10/2012}
"PAGE_NUMBER" = 79;
0"NC";
1"M_H_DQS_DN<17:0>";
2"M_H_DQS_DP<17:0>";
3"M_H_MA<17:0>";
4"M_H_DQ<63:0>";
5"M_H_BA<1:0>";
6"M_H_CLK_DP<3:0>";
7"M_H_BG<1:0>";
8"M_H_CS_N<7:0>";
9"M_H_CKE<3:0>";
10"M_H_CLK_DN<3:0>";
11"M_H_ODT<3:0>";
12"M_H_ECC<7:0>";
13"PVDDQ_GHJ\g";
14"PVTT_GHJ\g";
15"GND\g";
16"GND\g";
17"GND\g";
18"PVPP_GHJ\g";
19"PVPP_GHJ\g";
20"P12V_NVDIMM_GHJ\g";
21"GND\g";
22"M_H_VREF";
23"TP_CH_H_DIMM_H0_RFU_1";
24"TP_CH_H_DIMM_H0_RFU_0";
25"TP_CH_H_DIMM_H0_RFU_2";
26"SMB_DDR_GHJ_VPP_SCL";
27"SMB_DDR_GHJ_VPP_SDA";
28"FM_ADR_COMPLETE_GHJ_N";
29"M_H_ACT_N";
30"M_H_ALERT_N";
31"M_H_ECC<1>";
32"M_H_ECC<0>";
33"M_H_PAR";
34"FM_DIMM_EVENT_COD_N";
35"M_GHJ_RST_N";
36"M_H_ECC<3>";
37"M_H_ECC<2>";
38"M_H_ECC<5>";
39"M_H_ECC<4>";
40"M_H_ECC<7>";
41"M_H_ODT<1>";
42"M_H_ODT<0>";
43"M_H_ECC<6>";
44"M_H_CLK_DN<0>";
45"M_H_CS_N<0>";
46"M_H_CKE<0>";
47"M_H_CKE<1>";
48"M_H_CS_N<1>";
49"M_H_C<2>";
50"M_H_CS_N<3>";
51"M_H_CS_N<2>";
52"M_H_CLK_DN<1>";
53"M_H_BG<0>";
54"M_H_CLK_DP<0>";
55"M_H_CLK_DP<1>";
56"M_H_BA<0>";
57"M_H_BG<1>";
58"M_H_MA<0>";
59"M_H_BA<1>";
60"M_H_DQ<5>";
61"M_H_DQ<2>";
62"M_H_DQ<3>";
63"M_H_DQ<16>";
64"M_H_DQ<14>";
65"M_H_DQ<27>";
66"M_H_DQ<26>";
67"M_H_DQ<39>";
68"M_H_DQ<37>";
69"M_H_DQ<34>";
70"M_H_DQ<1>";
71"M_H_DQ<0>";
72"M_H_DQ<7>";
73"M_H_DQ<8>";
74"M_H_DQ<10>";
75"M_H_DQ<13>";
76"M_H_DQ<12>";
77"M_H_DQ<15>";
78"M_H_DQ<17>";
79"M_H_DQ<19>";
80"M_H_DQ<21>";
81"M_H_DQ<20>";
82"M_H_DQ<23>";
83"M_H_DQ<22>";
84"M_H_DQ<25>";
85"M_H_DQ<24>";
86"M_H_DQ<31>";
87"M_H_DQ<30>";
88"M_H_DQ<33>";
89"M_H_DQ<32>";
90"M_H_DQ<35>";
91"M_H_DQ<36>";
92"M_H_DQ<38>";
93"M_H_DQ<41>";
94"M_H_DQ<40>";
95"M_H_DQ<43>";
96"M_H_DQ<42>";
97"M_H_DQ<45>";
98"M_H_DQ<44>";
99"M_H_DQ<47>";
100"M_H_DQ<29>";
101"M_H_DQ<28>";
102"M_H_DQ<4>";
103"M_H_DQ<6>";
104"M_H_DQ<11>";
105"M_H_DQ<9>";
106"M_H_DQ<18>";
107"M_H_MA<2>";
108"M_H_MA<6>";
109"M_H_MA<5>";
110"M_H_MA<4>";
111"M_H_MA<3>";
112"M_H_MA<1>";
113"M_H_MA<11>";
114"M_H_MA<10>";
115"M_H_MA<9>";
116"M_H_MA<8>";
117"M_H_MA<7>";
118"M_H_MA<16>";
119"M_H_MA<15>";
120"M_H_MA<14>";
121"M_H_MA<13>";
122"M_H_MA<12>";
123"M_H_MA<17>";
124"M_H_DQ<62>";
125"M_H_DQ<63>";
126"M_H_DQ<60>";
127"M_H_DQ<46>";
128"M_H_DQ<49>";
129"M_H_DQ<48>";
130"M_H_DQ<51>";
131"M_H_DQ<50>";
132"M_H_DQ<53>";
133"M_H_DQ<52>";
134"M_H_DQ<55>";
135"M_H_DQ<59>";
136"M_H_DQ<56>";
137"M_H_DQ<54>";
138"M_H_DQ<57>";
139"M_H_DQ<58>";
140"M_H_DQ<61>";
141"M_H_DQS_DP<6>";
142"M_H_DQS_DN<6>";
143"M_H_DQS_DP<5>";
144"M_H_DQS_DN<5>";
145"M_H_DQS_DP<4>";
146"M_H_DQS_DN<4>";
147"M_H_DQS_DP<3>";
148"M_H_DQS_DN<3>";
149"M_H_DQS_DP<2>";
150"M_H_DQS_DN<2>";
151"M_H_DQS_DP<1>";
152"M_H_DQS_DN<1>";
153"M_H_DQS_DP<0>";
154"M_H_DQS_DN<0>";
155"M_H_DQS_DP<9>";
156"M_H_DQS_DN<9>";
157"M_H_DQS_DP<8>";
158"M_H_DQS_DN<8>";
159"M_H_DQS_DP<7>";
160"M_H_DQS_DN<7>";
161"M_H_DQS_DN<17>";
162"M_H_DQS_DP<16>";
163"M_H_DQS_DN<16>";
164"M_H_DQS_DP<15>";
165"M_H_DQS_DN<15>";
166"M_H_DQS_DP<14>";
167"M_H_DQS_DN<14>";
168"M_H_DQS_DP<13>";
169"M_H_DQS_DN<13>";
170"M_H_DQS_DP<12>";
171"M_H_DQS_DN<12>";
172"M_H_DQS_DP<11>";
173"M_H_DQS_DN<11>";
174"M_H_DQS_DP<10>";
175"M_H_DQS_DN<10>";
176"M_H_DQS_DP<17>";
%"TAP"
"6","(650,4950)","2","mstr_standard","I10";
;
HDL_TAP"TRUE"
BODY_TYPE"PLUMBING"
CDS_LIB"mstr_standard";
"B \NAC \NWC"2;
"S \NAC"
BN"15"164;
%"TAP"
"6","(-1850,2000)","2","mstr_standard","I100";
;
HDL_TAP"TRUE"
BODY_TYPE"PLUMBING"
CDS_LIB"mstr_standard";
"B \NAC \NWC"4;
"S \NAC"
BN"4"102;
%"TAP"
"6","(-1850,2100)","2","mstr_standard","I101";
;
HDL_TAP"TRUE"
BODY_TYPE"PLUMBING"
CDS_LIB"mstr_standard";
"B \NAC \NWC"4;
"S \NAC"
BN"6"103;
%"TAP"
"6","(-1850,2050)","2","mstr_standard","I102";
;
HDL_TAP"TRUE"
BODY_TYPE"PLUMBING"
CDS_LIB"mstr_standard";
"B \NAC \NWC"4;
"S \NAC"
BN"7"72;
%"TAP"
"6","(-1850,2150)","2","mstr_standard","I103";
;
HDL_TAP"TRUE"
BODY_TYPE"PLUMBING"
CDS_LIB"mstr_standard";
"B \NAC \NWC"4;
"S \NAC"
BN"9"105;
%"TAP"
"6","(-1850,2200)","2","mstr_standard","I104";
;
HDL_TAP"TRUE"
BODY_TYPE"PLUMBING"
CDS_LIB"mstr_standard";
"B \NAC \NWC"4;
"S \NAC"
BN"8"73;
%"TAP"
"6","(-1850,2250)","2","mstr_standard","I105";
;
HDL_TAP"TRUE"
BODY_TYPE"PLUMBING"
CDS_LIB"mstr_standard";
"B \NAC \NWC"4;
"S \NAC"
BN"11"104;
%"TAP"
"6","(-1850,1900)","2","mstr_standard","I106";
;
HDL_TAP"TRUE"
BODY_TYPE"PLUMBING"
CDS_LIB"mstr_standard";
"B \NAC \NWC"4;
"S \NAC"
BN"2"61;
%"TAP"
"6","(-1850,1950)","2","mstr_standard","I107";
;
HDL_TAP"TRUE"
BODY_TYPE"PLUMBING"
CDS_LIB"mstr_standard";
"B \NAC \NWC"4;
"S \NAC"
BN"5"60;
%"TAP"
"6","(-1850,1800)","2","mstr_standard","I108";
;
HDL_TAP"TRUE"
BODY_TYPE"PLUMBING"
CDS_LIB"mstr_standard";
"B \NAC \NWC"4;
"S \NAC"
BN"0"71;
%"TAP"
"6","(-1850,1750)","2","mstr_standard","I109";
;
HDL_TAP"TRUE"
BODY_TYPE"PLUMBING"
CDS_LIB"mstr_standard";
"B \NAC \NWC"4;
"S \NAC"
BN"1"70;
%"TAP"
"6","(650,4850)","2","mstr_standard","I11";
;
HDL_TAP"TRUE"
BODY_TYPE"PLUMBING"
CDS_LIB"mstr_standard";
"B \NAC \NWC"2;
"S \NAC"
BN"14"166;
%"TAP"
"6","(-1850,1850)","2","mstr_standard","I110";
;
HDL_TAP"TRUE"
BODY_TYPE"PLUMBING"
CDS_LIB"mstr_standard";
"B \NAC \NWC"4;
"S \NAC"
BN"3"62;
%"SCONN288_H44441004"
"1","(-2600,3250)","0","mstr_sconn","I111";
;
CDS_SEC"1"
ROOM"DDR4_CH_H"
CDS_LOCATION"J1G2"
SEC"1"
SEC_TYPE"PIP"
CDS_LIB"mstr_sconn"
BOM_COST"MEM"
PACK_TYPE"PIP"
MATERIAL"SCONN"
PART_NUMBER"H44441-004"
LOCATION"J1G2";
"DQ<63>"
$PN"280"124;
"DQ<62>"
$PN"135"125;
"DQ<61>"
$PN"273"126;
"DQ<5>"
$PN"148"102;
"DQ<4>"
$PN"3"60;
"DQ<3>"
$PN"157"61;
"DQ<2>"
$PN"12"62;
"DQ<47>"
$PN"258"127;
"DQ<48>"
$PN"119"128;
"DQ<49>"
$PN"264"129;
"DQ<50>"
$PN"126"130;
"DQ<51>"
$PN"271"131;
"DQ<52>"
$PN"117"132;
"DQ<53>"
$PN"262"133;
"DQ<54>"
$PN"124"134;
"DQ<58>"
$PN"137"135;
"DQ<57>"
$PN"275"136;
"SAVE_N_NC"
$PN"230"28;
"RFU<1>"
$PN"227"23;
"RFU<0>"
$PN"205"24;
"DQ<17>"
$PN"172"63;
"DQ<15>"
$PN"166"64;
"DQ<26>"
$PN"45"65;
"DQ<27>"
$PN"190"66;
"S0_N"
$PN"84"45;
"CKE<0>"
$PN"60"46;
"ODT<1>"
$PN"91"41;
"ODT<0>"
$PN"87"42;
"CB<7>"
$PN"199"43;
"A16_RAS_N"
$PN"82"118;
"A15_CAS_N"
$PN"86"119;
"A14_WE_N"
$PN"228"120;
"A11"
$PN"210"113;
"A10"
$PN"225"114;
"DQ<38>"
$PN"102"67;
"DQ<36>"
$PN"95"68;
"DQ<35>"
$PN"249"69;
"A2"
$PN"216"107;
"ALERT_N"
$PN"208"30;
"ACT_N"
$PN"62"29;
"DQ<0>"
$PN"5"70;
"DQ<1>"
$PN"150"71;
"SA<1>"
$PN"140"19;
"SA<2>"
$PN"238"16;
"VDDSPD"
$PN"284"19;
"SA<0>"
$PN"139"16;
"BA<0>"
$PN"81"56;
"BG<1>"
$PN"207"57;
"BG<0>"
$PN"63"53;
"CK1P"
$PN"218"55;
"VREFCA"
$PN"146"22;
"SDA"
$PN"285"27;
"SCL"
$PN"141"26;
"RFU<2>"
$PN"144"25;
"RESET_N"
$PN"58"35;
"PAR"
$PN"222"33;
"EVENT_N"
$PN"78"34;
"DQ<6>"
$PN"10"72;
"DQ<7>"
$PN"155"103;
"DQ<8>"
$PN"16"105;
"DQ<9>"
$PN"161"73;
"DQ<10>"
$PN"23"104;
"DQ<11>"
$PN"168"74;
"DQ<12>"
$PN"14"75;
"DQ<13>"
$PN"159"76;
"DQ<14>"
$PN"21"77;
"DQ<16>"
$PN"27"78;
"DQ<18>"
$PN"34"79;
"DQ<19>"
$PN"179"106;
"DQ<20>"
$PN"25"80;
"DQ<21>"
$PN"170"81;
"DQ<22>"
$PN"32"82;
"DQ<23>"
$PN"177"83;
"DQ<24>"
$PN"38"84;
"DQ<25>"
$PN"183"85;
"DQ<30>"
$PN"43"86;
"DQ<31>"
$PN"188"87;
"DQ<32>"
$PN"97"88;
"DQ<33>"
$PN"242"89;
"DQ<34>"
$PN"104"90;
"DQ<37>"
$PN"240"91;
"DQ<39>"
$PN"247"92;
"DQ<40>"
$PN"108"93;
"DQ<41>"
$PN"253"94;
"DQ<42>"
$PN"115"95;
"DQ<43>"
$PN"260"96;
"DQ<44>"
$PN"106"97;
"DQ<45>"
$PN"251"98;
"DQ<46>"
$PN"113"99;
"DQ<55>"
$PN"269"137;
"DQ<56>"
$PN"130"138;
"DQ<59>"
$PN"282"139;
"DQ<60>"
$PN"128"140;
"CKE<1>"
$PN"203"47;
"CK0N"
$PN"75"44;
"CB<0>"
$PN"49"31;
"CB<1>"
$PN"194"32;
"CB<2>"
$PN"56"36;
"CB<3>"
$PN"201"37;
"CB<4>"
$PN"47"38;
"CB<5>"
$PN"192"39;
"CB<6>"
$PN"54"40;
"A9"
$PN"66"115;
"A8"
$PN"68"116;
"A7"
$PN"211"117;
"A6"
$PN"69"108;
"A5"
$PN"213"109;
"A4"
$PN"214"110;
"A3"
$PN"71"111;
"A17"
$PN"234"123;
"A13"
$PN"232"121;
"A12"
$PN"65"122;
"A1"
$PN"72"112;
"A0"
$PN"79"58;
"C<2>"
$PN"235"49;
"DQ<28>"
$PN"36"100;
"DQ<29>"
$PN"181"101;
"S1_N"
$PN"89"48;
"S2_N_C<0>"
$PN"93"51;
"S3_N_C<1>"
$PN"237"50;
"CK0P"
$PN"74"54;
"CK1N"
$PN"219"52;
"BA<1>"
$PN"224"59;
%"TAP"
"6","(-3350,4850)","0","mstr_standard","I112";
;
HDL_TAP"TRUE"
BODY_TYPE"PLUMBING"
CDS_LIB"mstr_standard";
"B \NAC \NWC"3;
"S \NAC"
BN"16"118;
%"TAP"
"6","(-3350,4900)","0","mstr_standard","I113";
;
HDL_TAP"TRUE"
BODY_TYPE"PLUMBING"
CDS_LIB"mstr_standard";
"B \NAC \NWC"3;
"S \NAC"
BN"17"123;
%"TAP"
"6","(-3350,4800)","0","mstr_standard","I114";
;
HDL_TAP"TRUE"
BODY_TYPE"PLUMBING"
CDS_LIB"mstr_standard";
"B \NAC \NWC"3;
"S \NAC"
BN"15"119;
%"TAP"
"6","(-3350,4750)","0","mstr_standard","I115";
;
HDL_TAP"TRUE"
BODY_TYPE"PLUMBING"
CDS_LIB"mstr_standard";
"B \NAC \NWC"3;
"S \NAC"
BN"14"120;
%"TAP"
"6","(-3350,4700)","0","mstr_standard","I116";
;
HDL_TAP"TRUE"
BODY_TYPE"PLUMBING"
CDS_LIB"mstr_standard";
"B \NAC \NWC"3;
"S \NAC"
BN"13"121;
%"TAP"
"6","(-3350,4600)","0","mstr_standard","I117";
;
HDL_TAP"TRUE"
BODY_TYPE"PLUMBING"
CDS_LIB"mstr_standard";
"B \NAC \NWC"3;
"S \NAC"
BN"11"113;
%"TAP"
"6","(-3350,4650)","0","mstr_standard","I118";
;
HDL_TAP"TRUE"
BODY_TYPE"PLUMBING"
CDS_LIB"mstr_standard";
"B \NAC \NWC"3;
"S \NAC"
BN"12"122;
%"TAP"
"6","(-3350,4550)","0","mstr_standard","I119";
;
HDL_TAP"TRUE"
BODY_TYPE"PLUMBING"
CDS_LIB"mstr_standard";
"B \NAC \NWC"3;
"S \NAC"
BN"10"114;
%"TAP"
"6","(650,4750)","2","mstr_standard","I12";
;
HDL_TAP"TRUE"
BODY_TYPE"PLUMBING"
CDS_LIB"mstr_standard";
"B \NAC \NWC"2;
"S \NAC"
BN"13"168;
%"TAP"
"6","(-3350,4500)","0","mstr_standard","I120";
;
HDL_TAP"TRUE"
BODY_TYPE"PLUMBING"
CDS_LIB"mstr_standard";
"B \NAC \NWC"3;
"S \NAC"
BN"9"115;
%"TAP"
"6","(-3350,4450)","0","mstr_standard","I121";
;
HDL_TAP"TRUE"
BODY_TYPE"PLUMBING"
CDS_LIB"mstr_standard";
"B \NAC \NWC"3;
"S \NAC"
BN"8"116;
%"TAP"
"6","(-3350,4350)","0","mstr_standard","I122";
;
HDL_TAP"TRUE"
BODY_TYPE"PLUMBING"
CDS_LIB"mstr_standard";
"B \NAC \NWC"3;
"S \NAC"
BN"6"108;
%"TAP"
"6","(-3350,4400)","0","mstr_standard","I123";
;
HDL_TAP"TRUE"
BODY_TYPE"PLUMBING"
CDS_LIB"mstr_standard";
"B \NAC \NWC"3;
"S \NAC"
BN"7"117;
%"TAP"
"6","(-3350,4300)","0","mstr_standard","I124";
;
HDL_TAP"TRUE"
BODY_TYPE"PLUMBING"
CDS_LIB"mstr_standard";
"B \NAC \NWC"3;
"S \NAC"
BN"5"109;
%"TAP"
"6","(-3350,4200)","0","mstr_standard","I125";
;
HDL_TAP"TRUE"
BODY_TYPE"PLUMBING"
CDS_LIB"mstr_standard";
"B \NAC \NWC"3;
"S \NAC"
BN"3"111;
%"TAP"
"6","(-3350,4250)","0","mstr_standard","I126";
;
HDL_TAP"TRUE"
BODY_TYPE"PLUMBING"
CDS_LIB"mstr_standard";
"B \NAC \NWC"3;
"S \NAC"
BN"4"110;
%"TAP"
"6","(-3350,4150)","0","mstr_standard","I127";
;
HDL_TAP"TRUE"
BODY_TYPE"PLUMBING"
CDS_LIB"mstr_standard";
"B \NAC \NWC"3;
"S \NAC"
BN"2"107;
%"TAP"
"6","(-3350,4050)","0","mstr_standard","I128";
;
HDL_TAP"TRUE"
BODY_TYPE"PLUMBING"
CDS_LIB"mstr_standard";
"B \NAC \NWC"3;
"S \NAC"
BN"0"58;
%"TAP"
"6","(-3350,4100)","0","mstr_standard","I129";
;
HDL_TAP"TRUE"
BODY_TYPE"PLUMBING"
CDS_LIB"mstr_standard";
"B \NAC \NWC"3;
"S \NAC"
BN"1"112;
%"TAP"
"6","(650,4650)","2","mstr_standard","I13";
;
HDL_TAP"TRUE"
BODY_TYPE"PLUMBING"
CDS_LIB"mstr_standard";
"B \NAC \NWC"2;
"S \NAC"
BN"12"170;
%"TAP"
"6","(-3350,3950)","0","mstr_standard","I131";
;
HDL_TAP"TRUE"
BODY_TYPE"PLUMBING"
CDS_LIB"mstr_standard";
"B \NAC \NWC"5;
"S \NAC"
BN"1"59;
%"TAP"
"6","(-3350,3900)","0","mstr_standard","I132";
;
HDL_TAP"TRUE"
BODY_TYPE"PLUMBING"
CDS_LIB"mstr_standard";
"B \NAC \NWC"5;
"S \NAC"
BN"0"56;
%"TAP"
"6","(-3350,3800)","0","mstr_standard","I133";
;
HDL_TAP"TRUE"
BODY_TYPE"PLUMBING"
CDS_LIB"mstr_standard";
"B \NAC \NWC"7;
"S \NAC"
BN"0"53;
%"TAP"
"6","(-3350,3850)","0","mstr_standard","I134";
;
HDL_TAP"TRUE"
BODY_TYPE"PLUMBING"
CDS_LIB"mstr_standard";
"B \NAC \NWC"7;
"S \NAC"
BN"1"57;
%"TAP"
"6","(-3350,2800)","0","mstr_standard","I138";
;
HDL_TAP"TRUE"
BODY_TYPE"PLUMBING"
CDS_LIB"mstr_standard";
"B \NAC \NWC"12;
"S \NAC"
BN"7"40;
%"TAP"
"6","(-3350,2850)","0","mstr_standard","I139";
;
HDL_TAP"TRUE"
BODY_TYPE"PLUMBING"
CDS_LIB"mstr_standard";
"B \NAC \NWC"12;
"S \NAC"
BN"6"43;
%"PVDDQ_GHJ"
"1","(-1525,2525)","0","mstr_symbols","I14";
;
HDL_POWER"PVDDQ_GHJ"
ROOM"DDR4_CH_H"
BODY_TYPE"PLUMBING"
CDS_LIB"mstr_symbols"
BOM_COST"MEM"
VOLTAGE"1.2V";
"G\NAC"13;
%"TAP"
"6","(-3350,2750)","0","mstr_standard","I140";
;
HDL_TAP"TRUE"
BODY_TYPE"PLUMBING"
CDS_LIB"mstr_standard";
"B \NAC \NWC"12;
"S \NAC"
BN"4"39;
%"TAP"
"6","(-3350,2700)","0","mstr_standard","I141";
;
HDL_TAP"TRUE"
BODY_TYPE"PLUMBING"
CDS_LIB"mstr_standard";
"B \NAC \NWC"12;
"S \NAC"
BN"5"38;
%"TAP"
"6","(-3350,2650)","0","mstr_standard","I142";
;
HDL_TAP"TRUE"
BODY_TYPE"PLUMBING"
CDS_LIB"mstr_standard";
"B \NAC \NWC"12;
"S \NAC"
BN"2"37;
%"TAP"
"6","(-3350,2550)","0","mstr_standard","I143";
;
HDL_TAP"TRUE"
BODY_TYPE"PLUMBING"
CDS_LIB"mstr_standard";
"B \NAC \NWC"12;
"S \NAC"
BN"0"32;
%"TAP"
"6","(-3350,2600)","0","mstr_standard","I144";
;
HDL_TAP"TRUE"
BODY_TYPE"PLUMBING"
CDS_LIB"mstr_standard";
"B \NAC \NWC"12;
"S \NAC"
BN"3"36;
%"TAP"
"6","(-3350,2500)","0","mstr_standard","I145";
;
HDL_TAP"TRUE"
BODY_TYPE"PLUMBING"
CDS_LIB"mstr_standard";
"B \NAC \NWC"12;
"S \NAC"
BN"1"31;
%"TAP"
"6","(-3350,3700)","0","mstr_standard","I152";
;
HDL_TAP"TRUE"
BODY_TYPE"PLUMBING"
CDS_LIB"mstr_standard";
"B \NAC \NWC"6;
"S \NAC"
BN"1"55;
%"TAP"
"6","(-3350,3600)","0","mstr_standard","I153";
;
HDL_TAP"TRUE"
BODY_TYPE"PLUMBING"
CDS_LIB"mstr_standard";
"B \NAC \NWC"6;
"S \NAC"
BN"0"54;
%"TAP"
"6","(-3550,3650)","0","mstr_standard","I154";
;
HDL_TAP"TRUE"
BODY_TYPE"PLUMBING"
CDS_LIB"mstr_standard";
"B \NAC \NWC"10;
"S \NAC"
BN"1"52;
%"TAP"
"6","(-3550,3550)","0","mstr_standard","I155";
;
HDL_TAP"TRUE"
BODY_TYPE"PLUMBING"
CDS_LIB"mstr_standard";
"B \NAC \NWC"10;
"S \NAC"
BN"0"44;
%"TAP"
"6","(-3350,3400)","0","mstr_standard","I158";
;
HDL_TAP"TRUE"
BODY_TYPE"PLUMBING"
CDS_LIB"mstr_standard";
"B \NAC \NWC"8;
"S \NAC"
BN"3"50;
%"TAP"
"6","(-3350,3350)","0","mstr_standard","I159";
;
HDL_TAP"TRUE"
BODY_TYPE"PLUMBING"
CDS_LIB"mstr_standard";
"B \NAC \NWC"8;
"S \NAC"
BN"2"51;
%"PVTT_GHJ"
"1","(-1300,2700)","0","mstr_symbols","I16";
;
HDL_POWER"PVTT_GHJ"
ROOM"DDR4_CH_H"
BODY_TYPE"PLUMBING"
CDS_LIB"mstr_symbols"
BOM_COST"MEM"
VOLTAGE"0.6V";
"G\NAC"14;
%"TAP"
"6","(-3350,3300)","0","mstr_standard","I160";
;
HDL_TAP"TRUE"
BODY_TYPE"PLUMBING"
CDS_LIB"mstr_standard";
"B \NAC \NWC"8;
"S \NAC"
BN"1"48;
%"TAP"
"6","(-3350,3250)","0","mstr_standard","I161";
;
HDL_TAP"TRUE"
BODY_TYPE"PLUMBING"
CDS_LIB"mstr_standard";
"B \NAC \NWC"8;
"S \NAC"
BN"0"45;
%"TAP"
"6","(-3350,3150)","0","mstr_standard","I162";
;
HDL_TAP"TRUE"
BODY_TYPE"PLUMBING"
CDS_LIB"mstr_standard";
"B \NAC \NWC"9;
"S \NAC"
BN"1"47;
%"TAP"
"6","(-3350,3100)","0","mstr_standard","I163";
;
HDL_TAP"TRUE"
BODY_TYPE"PLUMBING"
CDS_LIB"mstr_standard";
"B \NAC \NWC"9;
"S \NAC"
BN"0"46;
%"TAP"
"6","(-3350,3000)","0","mstr_standard","I164";
;
HDL_TAP"TRUE"
BODY_TYPE"PLUMBING"
CDS_LIB"mstr_standard";
"B \NAC \NWC"11;
"S \NAC"
BN"1"41;
%"TAP"
"6","(-3350,2950)","0","mstr_standard","I168";
;
HDL_TAP"TRUE"
BODY_TYPE"PLUMBING"
CDS_LIB"mstr_standard";
"B \NAC \NWC"11;
"S \NAC"
BN"0"42;
%"SCONN288_H44441004"
"4","(-450,2000)","0","mstr_sconn","I169";
;
CDS_SEC"4"
ROOM"DDR4_CH_H"
CDS_LOCATION"J1G2"
SEC"4"
SEC_TYPE"PIP"
CDS_LIB"mstr_sconn"
BOM_COST"MEM"
PACK_TYPE"PIP"
MATERIAL"SCONN"
PART_NUMBER"H44441-004"
LOCATION"J1G2";
"VPP<4>"
$PN"142"18;
"VTT<1>"
$PN"77"14;
"VPP<0>"
$PN"287"18;
"VPP<1>"
$PN"286"18;
"VPP<2>"
$PN"288"18;
"VPP<3>"
$PN"143"18;
"VDD<1>"
$PN"233"13;
"VDD<2>"
$PN"231"13;
"VDD<3>"
$PN"229"13;
"VDD<4>"
$PN"226"13;
"VDD<5>"
$PN"223"13;
"VDD<7>"
$PN"217"13;
"VDD<8>"
$PN"215"13;
"VDD<9>"
$PN"212"13;
"VDD<11>"
$PN"206"13;
"VDD<12>"
$PN"204"13;
"VDD<14>"
$PN"90"13;
"VDD<15>"
$PN"88"13;
"VDD<17>"
$PN"83"13;
"VDD<18>"
$PN"80"13;
"VDD<20>"
$PN"73"13;
"VDD<21>"
$PN"70"13;
"VDD<22>"
$PN"67"13;
"VDD<24>"
$PN"61"13;
"12V<0>"
$PN"145"20;
"12V<1>"
$PN"1"20;
"VTT<0>"
$PN"221"14;
"VDD<25>"
$PN"59"13;
"VDD<23>"
$PN"64"13;
"VDD<19>"
$PN"76"13;
"VDD<16>"
$PN"85"13;
"VDD<13>"
$PN"92"13;
"VDD<10>"
$PN"209"13;
"VDD<6>"
$PN"220"13;
"VDD<0>"
$PN"236"13;
%"TAP"
"6","(850,4600)","2","mstr_standard","I17";
;
HDL_TAP"TRUE"
BODY_TYPE"PLUMBING"
CDS_LIB"mstr_standard";
"B \NAC \NWC"1;
"S \NAC"
BN"12"171;
%"GND"
"1","(2450,1100)","2","mstr_symbols","I170";
;
HDL_POWER"GND"
ROOM"DDR4_CH_H"
BODY_TYPE"PLUMBING"
BOM_COST"MEM"
SIZE"1B"
CDS_LIB"mstr_symbols"
VOLTAGE"0";
"A\NAC"15;
%"GND"
"1","(-5200,1900)","2","mstr_symbols","I175";
;
HDL_POWER"GND"
ROOM"DDR4_CH_H"
BODY_TYPE"PLUMBING"
BOM_COST"MEM"
SIZE"1B"
CDS_LIB"mstr_symbols"
VOLTAGE"0";
"A\NAC"16;
%"GND"
"1","(-4600,1300)","0","mstr_symbols","I177";
;
HDL_POWER"GND"
ROOM"DDR4_CH_H"
BODY_TYPE"PLUMBING"
CDS_LIB"mstr_symbols"
SIZE"1B"
BOM_COST"MEM"
VOLTAGE"0";
"A\NAC"17;
%"CAP_A"
"1","(-4600,1550)","2","dev_discrete","I178";
;
ROOM"DDR4_CH_J"
$SEC"1"
CDS_SEC"1"
CDS_LIB"dev_discrete"
BOM_COST"MEM"
CDS_LOCATION"C9U7"
MATERIAL"X7R"
VOLTAGE"25V"
PACK_TYPE"0402V"
TOLERANCE"10%"
VALUE"0.01UF"
PART_NUMBER"A36096-045"
LOCATION"C9U7";
"B"
$PN"2"17;
"A"
$PN"1"22;
%"PVPP_GHJ"
"1","(-1150,3000)","0","mstr_symbols","I179";
;
HDL_POWER"PVPP_GHJ"
ROOM"DDR4_CH_H"
BODY_TYPE"PLUMBING"
CDS_LIB"mstr_symbols"
BOM_COST"MEM"
VOLTAGE"2.5V";
"G\NAC"18;
%"TAP"
"6","(850,4500)","2","mstr_standard","I18";
;
HDL_TAP"TRUE"
BODY_TYPE"PLUMBING"
CDS_LIB"mstr_standard";
"B \NAC \NWC"1;
"S \NAC"
BN"11"173;
%"PVPP_GHJ"
"1","(-5200,2250)","0","mstr_symbols","I180";
;
HDL_POWER"PVPP_GHJ"
ROOM"DDR4_CH_H"
BODY_TYPE"PLUMBING"
CDS_LIB"mstr_symbols"
BOM_COST"MEM"
VOLTAGE"2.5V";
"G\NAC"19;
%"TAP"
"6","(650,3450)","2","mstr_standard","I185";
;
HDL_TAP"TRUE"
BODY_TYPE"PLUMBING"
CDS_LIB"mstr_standard";
"B \NAC \NWC"2;
"S \NAC"
BN"0"153;
%"P12V_NVDIMM_GHJ"
"1","(250,2975)","0","mstr_symbols","I186";
;
HDL_POWER"P12V_NVDIMM_GHJ"
BODY_TYPE"PLUMBING"
CDS_LIB"mstr_symbols"
VOLTAGE"12.0";
"G\NAC"20;
%"TAP"
"6","(850,4400)","2","mstr_standard","I19";
;
HDL_TAP"TRUE"
BODY_TYPE"PLUMBING"
CDS_LIB"mstr_standard";
"B \NAC \NWC"1;
"S \NAC"
BN"10"175;
%"TAP"
"6","(850,4200)","2","mstr_standard","I20";
;
HDL_TAP"TRUE"
BODY_TYPE"PLUMBING"
CDS_LIB"mstr_standard";
"B \NAC \NWC"1;
"S \NAC"
BN"8"158;
%"TAP"
"6","(850,4300)","2","mstr_standard","I21";
;
HDL_TAP"TRUE"
BODY_TYPE"PLUMBING"
CDS_LIB"mstr_standard";
"B \NAC \NWC"1;
"S \NAC"
BN"9"156;
%"TAP"
"6","(650,4550)","2","mstr_standard","I22";
;
HDL_TAP"TRUE"
BODY_TYPE"PLUMBING"
CDS_LIB"mstr_standard";
"B \NAC \NWC"2;
"S \NAC"
BN"11"172;
%"TAP"
"6","(650,4450)","2","mstr_standard","I23";
;
HDL_TAP"TRUE"
BODY_TYPE"PLUMBING"
CDS_LIB"mstr_standard";
"B \NAC \NWC"2;
"S \NAC"
BN"10"174;
%"TAP"
"6","(650,4350)","2","mstr_standard","I24";
;
HDL_TAP"TRUE"
BODY_TYPE"PLUMBING"
CDS_LIB"mstr_standard";
"B \NAC \NWC"2;
"S \NAC"
BN"9"155;
%"TAP"
"6","(650,4250)","2","mstr_standard","I25";
;
HDL_TAP"TRUE"
BODY_TYPE"PLUMBING"
CDS_LIB"mstr_standard";
"B \NAC \NWC"2;
"S \NAC"
BN"8"157;
%"TAP"
"6","(650,4150)","2","mstr_standard","I26";
;
HDL_TAP"TRUE"
BODY_TYPE"PLUMBING"
CDS_LIB"mstr_standard";
"B \NAC \NWC"2;
"S \NAC"
BN"7"159;
%"TAP"
"6","(850,4100)","2","mstr_standard","I27";
;
HDL_TAP"TRUE"
BODY_TYPE"PLUMBING"
CDS_LIB"mstr_standard";
"B \NAC \NWC"1;
"S \NAC"
BN"7"160;
%"TAP"
"6","(850,4000)","2","mstr_standard","I28";
;
HDL_TAP"TRUE"
BODY_TYPE"PLUMBING"
CDS_LIB"mstr_standard";
"B \NAC \NWC"1;
"S \NAC"
BN"6"142;
%"TAP"
"6","(850,3900)","2","mstr_standard","I29";
;
HDL_TAP"TRUE"
BODY_TYPE"PLUMBING"
CDS_LIB"mstr_standard";
"B \NAC \NWC"1;
"S \NAC"
BN"5"144;
%"TAP"
"6","(850,5100)","2","mstr_standard","I3";
;
HDL_TAP"TRUE"
BODY_TYPE"PLUMBING"
CDS_LIB"mstr_standard";
"B \NAC \NWC"1;
"S \NAC"
BN"17"161;
%"TAP"
"6","(850,3700)","2","mstr_standard","I30";
;
HDL_TAP"TRUE"
BODY_TYPE"PLUMBING"
CDS_LIB"mstr_standard";
"B \NAC \NWC"1;
"S \NAC"
BN"3"148;
%"TAP"
"6","(850,3800)","2","mstr_standard","I31";
;
HDL_TAP"TRUE"
BODY_TYPE"PLUMBING"
CDS_LIB"mstr_standard";
"B \NAC \NWC"1;
"S \NAC"
BN"4"146;
%"TAP"
"6","(650,4050)","2","mstr_standard","I32";
;
HDL_TAP"TRUE"
BODY_TYPE"PLUMBING"
CDS_LIB"mstr_standard";
"B \NAC \NWC"2;
"S \NAC"
BN"6"141;
%"TAP"
"6","(650,3950)","2","mstr_standard","I33";
;
HDL_TAP"TRUE"
BODY_TYPE"PLUMBING"
CDS_LIB"mstr_standard";
"B \NAC \NWC"2;
"S \NAC"
BN"5"143;
%"TAP"
"6","(650,3850)","2","mstr_standard","I34";
;
HDL_TAP"TRUE"
BODY_TYPE"PLUMBING"
CDS_LIB"mstr_standard";
"B \NAC \NWC"2;
"S \NAC"
BN"4"145;
%"TAP"
"6","(650,3750)","2","mstr_standard","I35";
;
HDL_TAP"TRUE"
BODY_TYPE"PLUMBING"
CDS_LIB"mstr_standard";
"B \NAC \NWC"2;
"S \NAC"
BN"3"147;
%"TAP"
"6","(650,3650)","2","mstr_standard","I36";
;
HDL_TAP"TRUE"
BODY_TYPE"PLUMBING"
CDS_LIB"mstr_standard";
"B \NAC \NWC"2;
"S \NAC"
BN"2"149;
%"TAP"
"6","(850,3500)","2","mstr_standard","I37";
;
HDL_TAP"TRUE"
BODY_TYPE"PLUMBING"
CDS_LIB"mstr_standard";
"B \NAC \NWC"1;
"S \NAC"
BN"1"152;
%"TAP"
"6","(850,3600)","2","mstr_standard","I38";
;
HDL_TAP"TRUE"
BODY_TYPE"PLUMBING"
CDS_LIB"mstr_standard";
"B \NAC \NWC"1;
"S \NAC"
BN"2"150;
%"TAP"
"6","(850,3400)","2","mstr_standard","I39";
;
HDL_TAP"TRUE"
BODY_TYPE"PLUMBING"
CDS_LIB"mstr_standard";
"B \NAC \NWC"1;
"S \NAC"
BN"0"154;
%"TAP"
"6","(850,5000)","2","mstr_standard","I4";
;
HDL_TAP"TRUE"
BODY_TYPE"PLUMBING"
CDS_LIB"mstr_standard";
"B \NAC \NWC"1;
"S \NAC"
BN"16"163;
%"TAP"
"6","(650,3550)","2","mstr_standard","I40";
;
HDL_TAP"TRUE"
BODY_TYPE"PLUMBING"
CDS_LIB"mstr_standard";
"B \NAC \NWC"2;
"S \NAC"
BN"1"151;
%"SCONN288_H44441004"
"3","(1750,2400)","0","mstr_sconn","I43";
;
CDS_SEC"3"
ROOM"DDR4_CH_H"
CDS_LOCATION"J1G2"
SEC"3"
SEC_TYPE"PIP"
CDS_LIB"mstr_sconn"
BOM_COST"MEM"
PACK_TYPE"PIP"
MATERIAL"SCONN"
PART_NUMBER"H44441-004"
LOCATION"J1G2";
"VSS<93>"
$PN"2"21;
"VSS<92>"
$PN"4"21;
"VSS<91>"
$PN"6"21;
"VSS<90>"
$PN"9"21;
"VSS<89>"
$PN"11"21;
"VSS<88>"
$PN"13"21;
"VSS<0>"
$PN"283"15;
"VSS<1>"
$PN"281"15;
"VSS<2>"
$PN"279"15;
"VSS<3>"
$PN"276"15;
"VSS<4>"
$PN"274"15;
"VSS<5>"
$PN"272"15;
"VSS<6>"
$PN"270"15;
"VSS<7>"
$PN"268"15;
"VSS<8>"
$PN"265"15;
"VSS<9>"
$PN"263"15;
"VSS<10>"
$PN"261"15;
"VSS<11>"
$PN"259"15;
"VSS<12>"
$PN"257"15;
"VSS<13>"
$PN"254"15;
"VSS<14>"
$PN"252"15;
"VSS<15>"
$PN"250"15;
"VSS<16>"
$PN"248"15;
"VSS<17>"
$PN"246"15;
"VSS<18>"
$PN"243"15;
"VSS<19>"
$PN"241"15;
"VSS<20>"
$PN"239"15;
"VSS<21>"
$PN"202"15;
"VSS<22>"
$PN"200"15;
"VSS<23>"
$PN"198"15;
"VSS<24>"
$PN"195"15;
"VSS<25>"
$PN"193"15;
"VSS<26>"
$PN"191"15;
"VSS<27>"
$PN"189"15;
"VSS<28>"
$PN"187"15;
"VSS<29>"
$PN"184"15;
"VSS<30>"
$PN"182"15;
"VSS<31>"
$PN"180"15;
"VSS<32>"
$PN"178"15;
"VSS<33>"
$PN"176"15;
"VSS<34>"
$PN"173"15;
"VSS<35>"
$PN"171"15;
"VSS<36>"
$PN"169"15;
"VSS<37>"
$PN"167"15;
"VSS<38>"
$PN"165"15;
"VSS<39>"
$PN"162"15;
"VSS<40>"
$PN"160"15;
"VSS<41>"
$PN"158"15;
"VSS<42>"
$PN"156"15;
"VSS<43>"
$PN"154"15;
"VSS<44>"
$PN"151"15;
"VSS<47>"
$PN"138"21;
"VSS<48>"
$PN"136"21;
"VSS<49>"
$PN"134"21;
"VSS<50>"
$PN"131"21;
"VSS<51>"
$PN"129"21;
"VSS<52>"
$PN"127"21;
"VSS<53>"
$PN"125"21;
"VSS<54>"
$PN"123"21;
"VSS<55>"
$PN"120"21;
"VSS<56>"
$PN"118"21;
"VSS<57>"
$PN"116"21;
"VSS<58>"
$PN"114"21;
"VSS<59>"
$PN"112"21;
"VSS<60>"
$PN"109"21;
"VSS<61>"
$PN"107"21;
"VSS<62>"
$PN"105"21;
"VSS<63>"
$PN"103"21;
"VSS<64>"
$PN"101"21;
"VSS<65>"
$PN"98"21;
"VSS<66>"
$PN"96"21;
"VSS<67>"
$PN"94"21;
"VSS<68>"
$PN"57"21;
"VSS<69>"
$PN"55"21;
"VSS<70>"
$PN"53"21;
"VSS<71>"
$PN"50"21;
"VSS<72>"
$PN"48"21;
"VSS<73>"
$PN"46"21;
"VSS<74>"
$PN"44"21;
"VSS<75>"
$PN"42"21;
"VSS<76>"
$PN"39"21;
"VSS<77>"
$PN"37"21;
"VSS<78>"
$PN"35"21;
"VSS<79>"
$PN"33"21;
"VSS<80>"
$PN"31"21;
"VSS<81>"
$PN"28"21;
"VSS<82>"
$PN"26"21;
"VSS<83>"
$PN"24"21;
"VSS<84>"
$PN"22"21;
"VSS<85>"
$PN"20"21;
"VSS<86>"
$PN"17"21;
"VSS<87>"
$PN"15"21;
"VSS<45>"
$PN"149"15;
"VSS<46>"
$PN"147"15;
%"GND"
"1","(1050,1100)","2","mstr_symbols","I44";
;
HDL_POWER"GND"
ROOM"DDR4_CH_H"
BODY_TYPE"PLUMBING"
BOM_COST"MEM"
SIZE"1B"
CDS_LIB"mstr_symbols"
VOLTAGE"0";
"A\NAC"21;
%"TAP"
"6","(-1850,4850)","2","mstr_standard","I46";
;
HDL_TAP"TRUE"
BODY_TYPE"PLUMBING"
CDS_LIB"mstr_standard";
"B \NAC \NWC"4;
"S \NAC"
BN"63"125;
%"TAP"
"6","(-1850,4900)","2","mstr_standard","I47";
;
HDL_TAP"TRUE"
BODY_TYPE"PLUMBING"
CDS_LIB"mstr_standard";
"B \NAC \NWC"4;
"S \NAC"
BN"62"124;
%"TAP"
"6","(-1850,4750)","2","mstr_standard","I48";
;
HDL_TAP"TRUE"
BODY_TYPE"PLUMBING"
CDS_LIB"mstr_standard";
"B \NAC \NWC"4;
"S \NAC"
BN"61"140;
%"TAP"
"6","(-1850,4800)","2","mstr_standard","I49";
;
HDL_TAP"TRUE"
BODY_TYPE"PLUMBING"
CDS_LIB"mstr_standard";
"B \NAC \NWC"4;
"S \NAC"
BN"60"126;
%"TAP"
"6","(850,4900)","2","mstr_standard","I5";
;
HDL_TAP"TRUE"
BODY_TYPE"PLUMBING"
CDS_LIB"mstr_standard";
"B \NAC \NWC"1;
"S \NAC"
BN"15"165;
%"TAP"
"6","(-1850,4700)","2","mstr_standard","I50";
;
HDL_TAP"TRUE"
BODY_TYPE"PLUMBING"
CDS_LIB"mstr_standard";
"B \NAC \NWC"4;
"S \NAC"
BN"58"139;
%"TAP"
"6","(-1850,4650)","2","mstr_standard","I51";
;
HDL_TAP"TRUE"
BODY_TYPE"PLUMBING"
CDS_LIB"mstr_standard";
"B \NAC \NWC"4;
"S \NAC"
BN"59"135;
%"TAP"
"6","(-1850,4600)","2","mstr_standard","I52";
;
HDL_TAP"TRUE"
BODY_TYPE"PLUMBING"
CDS_LIB"mstr_standard";
"B \NAC \NWC"4;
"S \NAC"
BN"56"136;
%"TAP"
"6","(-1850,4400)","2","mstr_standard","I53";
;
HDL_TAP"TRUE"
BODY_TYPE"PLUMBING"
CDS_LIB"mstr_standard";
"B \NAC \NWC"4;
"S \NAC"
BN"52"133;
%"TAP"
"6","(-1850,4450)","2","mstr_standard","I54";
;
HDL_TAP"TRUE"
BODY_TYPE"PLUMBING"
CDS_LIB"mstr_standard";
"B \NAC \NWC"4;
"S \NAC"
BN"55"134;
%"TAP"
"6","(-1850,4350)","2","mstr_standard","I55";
;
HDL_TAP"TRUE"
BODY_TYPE"PLUMBING"
CDS_LIB"mstr_standard";
"B \NAC \NWC"4;
"S \NAC"
BN"53"132;
%"TAP"
"6","(-1850,4500)","2","mstr_standard","I56";
;
HDL_TAP"TRUE"
BODY_TYPE"PLUMBING"
CDS_LIB"mstr_standard";
"B \NAC \NWC"4;
"S \NAC"
BN"54"137;
%"TAP"
"6","(-1850,4550)","2","mstr_standard","I57";
;
HDL_TAP"TRUE"
BODY_TYPE"PLUMBING"
CDS_LIB"mstr_standard";
"B \NAC \NWC"4;
"S \NAC"
BN"57"138;
%"TAP"
"6","(-1850,4100)","2","mstr_standard","I58";
;
HDL_TAP"TRUE"
BODY_TYPE"PLUMBING"
CDS_LIB"mstr_standard";
"B \NAC \NWC"4;
"S \NAC"
BN"46"127;
%"TAP"
"6","(-1850,4150)","2","mstr_standard","I59";
;
HDL_TAP"TRUE"
BODY_TYPE"PLUMBING"
CDS_LIB"mstr_standard";
"B \NAC \NWC"4;
"S \NAC"
BN"49"128;
%"TAP"
"6","(850,4800)","2","mstr_standard","I6";
;
HDL_TAP"TRUE"
BODY_TYPE"PLUMBING"
CDS_LIB"mstr_standard";
"B \NAC \NWC"1;
"S \NAC"
BN"14"167;
%"TAP"
"6","(-1850,4050)","2","mstr_standard","I60";
;
HDL_TAP"TRUE"
BODY_TYPE"PLUMBING"
CDS_LIB"mstr_standard";
"B \NAC \NWC"4;
"S \NAC"
BN"47"99;
%"TAP"
"6","(-1850,4200)","2","mstr_standard","I61";
;
HDL_TAP"TRUE"
BODY_TYPE"PLUMBING"
CDS_LIB"mstr_standard";
"B \NAC \NWC"4;
"S \NAC"
BN"48"129;
%"TAP"
"6","(-1850,4250)","2","mstr_standard","I62";
;
HDL_TAP"TRUE"
BODY_TYPE"PLUMBING"
CDS_LIB"mstr_standard";
"B \NAC \NWC"4;
"S \NAC"
BN"51"130;
%"TAP"
"6","(-1850,4300)","2","mstr_standard","I63";
;
HDL_TAP"TRUE"
BODY_TYPE"PLUMBING"
CDS_LIB"mstr_standard";
"B \NAC \NWC"4;
"S \NAC"
BN"50"131;
%"SCONN288_H44441004"
"2","(-50,4300)","0","mstr_sconn","I64";
;
CDS_SEC"2"
ROOM"DDR4_CH_H"
CDS_LOCATION"J1G2"
SEC"2"
SEC_TYPE"PIP"
CDS_LIB"mstr_sconn"
BOM_COST"MEM"
PACK_TYPE"PIP"
MATERIAL"SCONN"
PART_NUMBER"H44441-004"
LOCATION"J1G2";
"DQS17P"
$PN"51"176;
"DQS9P"
$PN"7"155;
"DQS9N"
$PN"8"156;
"DQS8P"
$PN"197"157;
"DQS8N"
$PN"196"158;
"DQS7P"
$PN"278"159;
"DQS7N"
$PN"277"160;
"DQS6P"
$PN"267"141;
"DQS6N"
$PN"266"142;
"DQS5P"
$PN"256"143;
"DQS5N"
$PN"255"144;
"DQS4P"
$PN"245"145;
"DQS4N"
$PN"244"146;
"DQS3P"
$PN"186"147;
"DQS3N"
$PN"185"148;
"DQS2P"
$PN"175"149;
"DQS2N"
$PN"174"150;
"DQS1P"
$PN"164"151;
"DQS1N"
$PN"163"152;
"DQS17N"
$PN"52"161;
"DQS16P"
$PN"132"162;
"DQS16N"
$PN"133"163;
"DQS15P"
$PN"121"164;
"DQS15N"
$PN"122"165;
"DQS14P"
$PN"110"166;
"DQS14N"
$PN"111"167;
"DQS13P"
$PN"99"168;
"DQS13N"
$PN"100"169;
"DQS12P"
$PN"40"170;
"DQS12N"
$PN"41"171;
"DQS11P"
$PN"29"172;
"DQS11N"
$PN"30"173;
"DQS10P"
$PN"18"174;
"DQS10N"
$PN"19"175;
"DQS0P"
$PN"153"153;
"DQS0N"
$PN"152"154;
%"TAP"
"6","(-1850,3900)","2","mstr_standard","I65";
;
HDL_TAP"TRUE"
BODY_TYPE"PLUMBING"
CDS_LIB"mstr_standard";
"B \NAC \NWC"4;
"S \NAC"
BN"42"96;
%"TAP"
"6","(-1850,3850)","2","mstr_standard","I66";
;
HDL_TAP"TRUE"
BODY_TYPE"PLUMBING"
CDS_LIB"mstr_standard";
"B \NAC \NWC"4;
"S \NAC"
BN"43"95;
%"TAP"
"6","(-1850,3800)","2","mstr_standard","I67";
;
HDL_TAP"TRUE"
BODY_TYPE"PLUMBING"
CDS_LIB"mstr_standard";
"B \NAC \NWC"4;
"S \NAC"
BN"40"94;
%"TAP"
"6","(-1850,3950)","2","mstr_standard","I68";
;
HDL_TAP"TRUE"
BODY_TYPE"PLUMBING"
CDS_LIB"mstr_standard";
"B \NAC \NWC"4;
"S \NAC"
BN"45"97;
%"TAP"
"6","(-1850,4000)","2","mstr_standard","I69";
;
HDL_TAP"TRUE"
BODY_TYPE"PLUMBING"
CDS_LIB"mstr_standard";
"B \NAC \NWC"4;
"S \NAC"
BN"44"98;
%"TAP"
"6","(850,4700)","2","mstr_standard","I7";
;
HDL_TAP"TRUE"
BODY_TYPE"PLUMBING"
CDS_LIB"mstr_standard";
"B \NAC \NWC"1;
"S \NAC"
BN"13"169;
%"TAP"
"6","(-1850,3650)","2","mstr_standard","I70";
;
HDL_TAP"TRUE"
BODY_TYPE"PLUMBING"
CDS_LIB"mstr_standard";
"B \NAC \NWC"4;
"S \NAC"
BN"39"67;
%"TAP"
"6","(-1850,3600)","2","mstr_standard","I71";
;
HDL_TAP"TRUE"
BODY_TYPE"PLUMBING"
CDS_LIB"mstr_standard";
"B \NAC \NWC"4;
"S \NAC"
BN"36"91;
%"TAP"
"6","(-1850,3550)","2","mstr_standard","I72";
;
HDL_TAP"TRUE"
BODY_TYPE"PLUMBING"
CDS_LIB"mstr_standard";
"B \NAC \NWC"4;
"S \NAC"
BN"37"68;
%"TAP"
"6","(-1850,3750)","2","mstr_standard","I73";
;
HDL_TAP"TRUE"
BODY_TYPE"PLUMBING"
CDS_LIB"mstr_standard";
"B \NAC \NWC"4;
"S \NAC"
BN"41"93;
%"TAP"
"6","(-1850,3700)","2","mstr_standard","I74";
;
HDL_TAP"TRUE"
BODY_TYPE"PLUMBING"
CDS_LIB"mstr_standard";
"B \NAC \NWC"4;
"S \NAC"
BN"38"92;
%"TAP"
"6","(-1850,3400)","2","mstr_standard","I75";
;
HDL_TAP"TRUE"
BODY_TYPE"PLUMBING"
CDS_LIB"mstr_standard";
"B \NAC \NWC"4;
"S \NAC"
BN"32"89;
%"TAP"
"6","(-1850,3350)","2","mstr_standard","I76";
;
HDL_TAP"TRUE"
BODY_TYPE"PLUMBING"
CDS_LIB"mstr_standard";
"B \NAC \NWC"4;
"S \NAC"
BN"33"88;
%"TAP"
"6","(-1850,3300)","2","mstr_standard","I77";
;
HDL_TAP"TRUE"
BODY_TYPE"PLUMBING"
CDS_LIB"mstr_standard";
"B \NAC \NWC"4;
"S \NAC"
BN"30"87;
%"TAP"
"6","(-1850,3500)","2","mstr_standard","I78";
;
HDL_TAP"TRUE"
BODY_TYPE"PLUMBING"
CDS_LIB"mstr_standard";
"B \NAC \NWC"4;
"S \NAC"
BN"34"69;
%"TAP"
"6","(-1850,3450)","2","mstr_standard","I79";
;
HDL_TAP"TRUE"
BODY_TYPE"PLUMBING"
CDS_LIB"mstr_standard";
"B \NAC \NWC"4;
"S \NAC"
BN"35"90;
%"TAP"
"6","(650,5050)","2","mstr_standard","I8";
;
HDL_TAP"TRUE"
BODY_TYPE"PLUMBING"
CDS_LIB"mstr_standard";
"B \NAC \NWC"2;
"S \NAC"
BN"16"162;
%"TAP"
"6","(-1850,3100)","2","mstr_standard","I80";
;
HDL_TAP"TRUE"
BODY_TYPE"PLUMBING"
CDS_LIB"mstr_standard";
"B \NAC \NWC"4;
"S \NAC"
BN"26"66;
%"TAP"
"6","(-1850,3150)","2","mstr_standard","I81";
;
HDL_TAP"TRUE"
BODY_TYPE"PLUMBING"
CDS_LIB"mstr_standard";
"B \NAC \NWC"4;
"S \NAC"
BN"29"100;
%"TAP"
"6","(-1850,3050)","2","mstr_standard","I82";
;
HDL_TAP"TRUE"
BODY_TYPE"PLUMBING"
CDS_LIB"mstr_standard";
"B \NAC \NWC"4;
"S \NAC"
BN"27"65;
%"TAP"
"6","(-1850,3200)","2","mstr_standard","I83";
;
HDL_TAP"TRUE"
BODY_TYPE"PLUMBING"
CDS_LIB"mstr_standard";
"B \NAC \NWC"4;
"S \NAC"
BN"28"101;
%"TAP"
"6","(-1850,3250)","2","mstr_standard","I84";
;
HDL_TAP"TRUE"
BODY_TYPE"PLUMBING"
CDS_LIB"mstr_standard";
"B \NAC \NWC"4;
"S \NAC"
BN"31"86;
%"TAP"
"6","(-1850,2850)","2","mstr_standard","I85";
;
HDL_TAP"TRUE"
BODY_TYPE"PLUMBING"
CDS_LIB"mstr_standard";
"B \NAC \NWC"4;
"S \NAC"
BN"23"82;
%"TAP"
"6","(-1850,2900)","2","mstr_standard","I86";
;
HDL_TAP"TRUE"
BODY_TYPE"PLUMBING"
CDS_LIB"mstr_standard";
"B \NAC \NWC"4;
"S \NAC"
BN"22"83;
%"TAP"
"6","(-1850,2800)","2","mstr_standard","I87";
;
HDL_TAP"TRUE"
BODY_TYPE"PLUMBING"
CDS_LIB"mstr_standard";
"B \NAC \NWC"4;
"S \NAC"
BN"20"81;
%"TAP"
"6","(-1850,3000)","2","mstr_standard","I88";
;
HDL_TAP"TRUE"
BODY_TYPE"PLUMBING"
CDS_LIB"mstr_standard";
"B \NAC \NWC"4;
"S \NAC"
BN"24"85;
%"TAP"
"6","(-1850,2950)","2","mstr_standard","I89";
;
HDL_TAP"TRUE"
BODY_TYPE"PLUMBING"
CDS_LIB"mstr_standard";
"B \NAC \NWC"4;
"S \NAC"
BN"25"84;
%"TAP"
"6","(650,5150)","2","mstr_standard","I9";
;
HDL_TAP"TRUE"
BODY_TYPE"PLUMBING"
CDS_LIB"mstr_standard";
"B \NAC \NWC"2;
"S \NAC"
BN"17"176;
%"TAP"
"6","(-1850,2550)","2","mstr_standard","I90";
;
HDL_TAP"TRUE"
BODY_TYPE"PLUMBING"
CDS_LIB"mstr_standard";
"B \NAC \NWC"4;
"S \NAC"
BN"17"78;
%"TAP"
"6","(-1850,2600)","2","mstr_standard","I91";
;
HDL_TAP"TRUE"
BODY_TYPE"PLUMBING"
CDS_LIB"mstr_standard";
"B \NAC \NWC"4;
"S \NAC"
BN"16"63;
%"TAP"
"6","(-1850,2650)","2","mstr_standard","I92";
;
HDL_TAP"TRUE"
BODY_TYPE"PLUMBING"
CDS_LIB"mstr_standard";
"B \NAC \NWC"4;
"S \NAC"
BN"19"79;
%"TAP"
"6","(-1850,2700)","2","mstr_standard","I93";
;
HDL_TAP"TRUE"
BODY_TYPE"PLUMBING"
CDS_LIB"mstr_standard";
"B \NAC \NWC"4;
"S \NAC"
BN"18"106;
%"TAP"
"6","(-1850,2750)","2","mstr_standard","I94";
;
HDL_TAP"TRUE"
BODY_TYPE"PLUMBING"
CDS_LIB"mstr_standard";
"B \NAC \NWC"4;
"S \NAC"
BN"21"80;
%"TAP"
"6","(-1850,2300)","2","mstr_standard","I95";
;
HDL_TAP"TRUE"
BODY_TYPE"PLUMBING"
CDS_LIB"mstr_standard";
"B \NAC \NWC"4;
"S \NAC"
BN"10"74;
%"TAP"
"6","(-1850,2400)","2","mstr_standard","I96";
;
HDL_TAP"TRUE"
BODY_TYPE"PLUMBING"
CDS_LIB"mstr_standard";
"B \NAC \NWC"4;
"S \NAC"
BN"12"76;
%"TAP"
"6","(-1850,2350)","2","mstr_standard","I97";
;
HDL_TAP"TRUE"
BODY_TYPE"PLUMBING"
CDS_LIB"mstr_standard";
"B \NAC \NWC"4;
"S \NAC"
BN"13"75;
%"TAP"
"6","(-1850,2450)","2","mstr_standard","I98";
;
HDL_TAP"TRUE"
BODY_TYPE"PLUMBING"
CDS_LIB"mstr_standard";
"B \NAC \NWC"4;
"S \NAC"
BN"15"77;
%"TAP"
"6","(-1850,2500)","2","mstr_standard","I99";
;
HDL_TAP"TRUE"
BODY_TYPE"PLUMBING"
CDS_LIB"mstr_standard";
"B \NAC \NWC"4;
"S \NAC"
BN"14"64;
END.
